(kicad_pcb
	(version 20260206)
	(generator "pcbnew")
	(generator_version "10.0")
	(general
		(thickness 1.6)
		(legacy_teardrops no)
	)
	(paper "A4")
	(title_block
		(title "Bryce Canyon_SCC_16316-1_OCP.brd")
		(comment 1 "Bryce Canyon / footprints 675-681 of 1561")
	)
	(layers
		(0 "F.Cu" signal "TOP")
		(4 "In1.Cu" signal "L2GND")
		(6 "In2.Cu" signal "L3")
		(8 "In3.Cu" signal "L4VCC")
		(10 "In4.Cu" signal "L5VCC")
		(12 "In5.Cu" signal "L6")
		(14 "In6.Cu" signal "L7GND")
		(2 "B.Cu" signal "BOTTOM")
		(9 "F.Adhes" user "F.Adhesive")
		(11 "B.Adhes" user "B.Adhesive")
		(13 "F.Paste" user "Package Geometry/Pastemask Top")
		(15 "B.Paste" user "Package Geometry/Pastemask Bottom")
		(5 "F.SilkS" user "Ref Des/Silkscreen Top")
		(7 "B.SilkS" user "Ref Des/Silkscreen Bottom")
		(1 "F.Mask" user "Board Geometry/Soldermask Top")
		(3 "B.Mask" user "Board Geometry/Soldermask Bottom")
		(17 "Dwgs.User" user "User.Drawings")
		(19 "Cmts.User" user "User.Comments")
		(21 "Eco1.User" user "User.Eco1")
		(23 "Eco2.User" user "User.Eco2")
		(25 "Edge.Cuts" user "Board Geometry/Outline")
		(27 "Margin" user)
		(31 "F.CrtYd" user "Package Geometry/Place Bound Top")
		(29 "B.CrtYd" user "Package Geometry/Place Bound Bottom")
		(35 "F.Fab" user "Ref Des/Assembly Top")
		(33 "B.Fab" user "Ref Des/Assembly Bottom")
	)
	(footprint ""
		(layer "F.Cu")
		(at 128.5748 -89.916)
		(property "Reference" "R118"
			(at 0 0 0)
			(layer "F.SilkS")
			(hide yes)
			(effects
				(font
					(size 1.27 1.27)
				)
			)
		)
		(property "Value" "4K75R2F-1-GP"
			(at 0.064008 -3.993896 0)
			(unlocked yes)
			(layer "F.Fab")
			(hide yes)
			(effects
				(font
					(size 1.016 1.016)
					(thickness 0.1524)
				)
			)
		)
		(property "Device Type" "R402H16"
			(at 0.064008 -5.517896 0)
			(unlocked yes)
			(layer "F.Fab")
			(hide yes)
			(effects
				(font
					(size 1.016 1.016)
					(thickness 0.1524)
				)
			)
		)
		(duplicate_pad_numbers_are_jumpers no)
		(fp_line
			(start -0.508 -0.9398)
			(end -0.508 0.9398)
			(stroke
				(width 0.1524)
				(type default)
			)
			(layer "F.SilkS")
		)
		(fp_line
			(start 0.508 -0.9398)
			(end -0.508 -0.9398)
			(stroke
				(width 0.1524)
				(type default)
			)
			(layer "F.SilkS")
		)
		(fp_rect
			(start -0.508 0.9398)
			(end 0.508 -0.9398)
			(stroke
				(width 0)
				(type default)
			)
			(fill no)
			(layer "F.CrtYd")
		)
		(fp_rect
			(start -0.508 0.9398)
			(end 0.508 -0.9398)
			(stroke
				(width 0)
				(type default)
			)
			(fill no)
			(layer "F.Fab")
		)
		(pad "1" smd custom
			(at 0 -0.4445)
			(size 0.1397 0.1397)
			(layers "F.Cu" "F.Mask" "F.Paste")
			(net "P1V8_E")
			(options
				(clearance outline)
				(anchor circle)
			)
			(primitives
				(gr_poly
					(pts
						(arc
							(start -0.1778 -0.2794)
							(mid -0.249642 -0.249642)
							(end -0.2794 -0.1778)
						)
						(arc
							(start -0.2794 0.1778)
							(mid -0.249642 0.249642)
							(end -0.1778 0.2794)
						)
						(arc
							(start 0.1778 0.2794)
							(mid 0.249642 0.249642)
							(end 0.2794 0.1778)
						)
						(arc
							(start 0.2794 -0.1778)
							(mid 0.249642 -0.249642)
							(end 0.1778 -0.2794)
						)
					)
					(width 0)
					(fill yes)
				)
			)
		)
		(pad "2" smd custom
			(at 0 0.4445)
			(size 0.1397 0.1397)
			(layers "F.Cu" "F.Mask" "F.Paste")
			(net "SAS_SMART_TX")
			(options
				(clearance outline)
				(anchor circle)
			)
			(primitives
				(gr_poly
					(pts
						(arc
							(start -0.1778 -0.2794)
							(mid -0.249642 -0.249642)
							(end -0.2794 -0.1778)
						)
						(arc
							(start -0.2794 0.1778)
							(mid -0.249642 0.249642)
							(end -0.1778 0.2794)
						)
						(arc
							(start 0.1778 0.2794)
							(mid 0.249642 0.249642)
							(end 0.2794 0.1778)
						)
						(arc
							(start 0.2794 -0.1778)
							(mid 0.249642 -0.249642)
							(end 0.1778 -0.2794)
						)
					)
					(width 0)
					(fill yes)
				)
			)
		)
	)
	(footprint ""
		(layer "F.Cu")
		(at 181.821836 -122.7836 90)
		(property "Reference" "C686"
			(at 0 0 90)
			(layer "F.SilkS")
			(hide yes)
			(effects
				(font
					(size 1.27 1.27)
				)
			)
		)
		(property "Value" "SC10U6D3V5KX-4GP"
			(at -0.0762 -6.1214 90)
			(unlocked yes)
			(layer "F.Fab")
			(hide yes)
			(effects
				(font
					(size 1.016 1.016)
					(thickness 0.1524)
				)
			)
		)
		(property "Device Type" "C805H58"
			(at -0.0762 -8.1534 90)
			(unlocked yes)
			(layer "F.Fab")
			(hide yes)
			(effects
				(font
					(size 1.016 1.016)
					(thickness 0.1524)
				)
			)
		)
		(duplicate_pad_numbers_are_jumpers no)
		(fp_line
			(start 0.635 0)
			(end -0.635 0)
			(stroke
				(width 0.508)
				(type default)
			)
			(layer "F.SilkS")
		)
		(fp_rect
			(start -0.9652 1.778)
			(end 0.9652 -1.778)
			(stroke
				(width 0)
				(type default)
			)
			(fill no)
			(layer "F.CrtYd")
		)
		(fp_poly
			(pts
				(xy -0.9652 -1.778) (xy 0.9652 -1.778) (xy 0.9652 1.778) (xy -0.9652 1.778)
			)
			(stroke
				(width 0)
				(type default)
			)
			(fill no)
			(layer "F.Fab")
		)
		(pad "1" smd rect
			(at 0 -0.9652 90)
			(size 1.397 1.143)
			(layers "F.Cu" "F.Mask" "F.Paste")
			(net "P1V8_E_OUT")
		)
		(pad "2" smd rect
			(at 0 0.9652 90)
			(size 1.397 1.143)
			(layers "F.Cu" "F.Mask" "F.Paste")
			(net "GND")
		)
	)
	(footprint ""
		(layer "F.Cu")
		(at 136.2456 -80.5688 90)
		(property "Reference" "C610"
			(at 0 0 90)
			(layer "F.SilkS")
			(hide yes)
			(effects
				(font
					(size 1.27 1.27)
				)
			)
		)
		(property "Value" "SCD01U16V1KX-GP"
			(at -2.8321 -1.7399 90)
			(unlocked yes)
			(layer "F.Fab")
			(hide yes)
			(effects
				(font
					(size 1.016 1.016)
					(thickness 0.1524)
				)
			)
		)
		(property "Device Type" "C0201H13"
			(at -2.8321 -3.2639 90)
			(unlocked yes)
			(layer "F.Fab")
			(hide yes)
			(effects
				(font
					(size 1.016 1.016)
					(thickness 0.1524)
				)
			)
		)
		(duplicate_pad_numbers_are_jumpers no)
		(fp_rect
			(start -0.2794 0.6477)
			(end 0.2794 -0.6477)
			(stroke
				(width 0)
				(type default)
			)
			(fill no)
			(layer "F.CrtYd")
		)
		(fp_rect
			(start -0.2794 0.6477)
			(end 0.2794 -0.6477)
			(stroke
				(width 0)
				(type default)
			)
			(fill no)
			(layer "F.Fab")
		)
		(pad "1" smd custom
			(at 0 -0.2794 90)
			(size 0.0762 0.0762)
			(layers "F.Cu" "F.Mask" "F.Paste")
			(net "PHY_EXP_TO_CONN_C_11_DP")
			(options
				(clearance outline)
				(anchor circle)
			)
			(primitives
				(gr_poly
					(pts
						(arc
							(start 0.1524 -0.127)
							(mid 0.137521 -0.162921)
							(end 0.1016 -0.1778)
						)
						(arc
							(start -0.1016 -0.1778)
							(mid -0.137521 -0.162921)
							(end -0.1524 -0.127)
						)
						(arc
							(start -0.1524 0.127)
							(mid -0.137521 0.162921)
							(end -0.1016 0.1778)
						)
						(arc
							(start 0.1016 0.1778)
							(mid 0.137521 0.162921)
							(end 0.1524 0.127)
						)
					)
					(width 0)
					(fill yes)
				)
			)
		)
		(pad "2" smd custom
			(at 0 0.2794 90)
			(size 0.0762 0.0762)
			(layers "F.Cu" "F.Mask" "F.Paste")
			(net "PHY_EXP_TO_CONN_11_DP")
			(options
				(clearance outline)
				(anchor circle)
			)
			(primitives
				(gr_poly
					(pts
						(arc
							(start 0.1524 -0.127)
							(mid 0.137521 -0.162921)
							(end 0.1016 -0.1778)
						)
						(arc
							(start -0.1016 -0.1778)
							(mid -0.137521 -0.162921)
							(end -0.1524 -0.127)
						)
						(arc
							(start -0.1524 0.127)
							(mid -0.137521 0.162921)
							(end -0.1016 0.1778)
						)
						(arc
							(start 0.1016 0.1778)
							(mid 0.137521 0.162921)
							(end 0.1524 0.127)
						)
					)
					(width 0)
					(fill yes)
				)
			)
		)
	)
	(footprint ""
		(layer "F.Cu")
		(at 17.3736 -46.9646)
		(property "Reference" "C650"
			(at 0 0 0)
			(layer "F.SilkS")
			(hide yes)
			(effects
				(font
					(size 1.27 1.27)
				)
			)
		)
		(property "Value" "SC1U16V3KX-5GP"
			(at 0 -2.8194 0)
			(unlocked yes)
			(layer "F.Fab")
			(hide yes)
			(effects
				(font
					(size 1.016 1.016)
					(thickness 0.1524)
				)
			)
		)
		(property "Device Type" "C603H36"
			(at 0 -4.3434 0)
			(unlocked yes)
			(layer "F.Fab")
			(hide yes)
			(effects
				(font
					(size 1.016 1.016)
					(thickness 0.1524)
				)
			)
		)
		(duplicate_pad_numbers_are_jumpers no)
		(fp_line
			(start 0.508 0)
			(end -0.508 0)
			(stroke
				(width 0.2032)
				(type default)
			)
			(layer "F.SilkS")
		)
		(fp_rect
			(start -0.5842 1.3335)
			(end 0.5842 -1.3335)
			(stroke
				(width 0)
				(type default)
			)
			(fill no)
			(layer "F.CrtYd")
		)
		(fp_rect
			(start -0.5842 1.3335)
			(end 0.5842 -1.3335)
			(stroke
				(width 0)
				(type default)
			)
			(fill no)
			(layer "F.Fab")
		)
		(pad "1" smd custom
			(at 0 -0.762)
			(size 0.2159 0.2159)
			(layers "F.Cu" "F.Mask" "F.Paste")
			(net "MB0_CM_UV_R")
			(options
				(clearance outline)
				(anchor circle)
			)
			(primitives
				(gr_poly
					(pts
						(arc
							(start -0.3302 -0.4318)
							(mid -0.402042 -0.402042)
							(end -0.4318 -0.3302)
						)
						(arc
							(start -0.4318 0.3302)
							(mid -0.402042 0.402042)
							(end -0.3302 0.4318)
						)
						(arc
							(start 0.3302 0.4318)
							(mid 0.402042 0.402042)
							(end 0.4318 0.3302)
						)
						(arc
							(start 0.4318 -0.3302)
							(mid 0.402042 -0.402042)
							(end 0.3302 -0.4318)
						)
					)
					(width 0)
					(fill yes)
				)
			)
		)
		(pad "2" smd custom
			(at 0 0.762)
			(size 0.2159 0.2159)
			(layers "F.Cu" "F.Mask" "F.Paste")
			(net "AGND_CURRENT_MON")
			(options
				(clearance outline)
				(anchor circle)
			)
			(primitives
				(gr_poly
					(pts
						(arc
							(start -0.3302 -0.4318)
							(mid -0.402042 -0.402042)
							(end -0.4318 -0.3302)
						)
						(arc
							(start -0.4318 0.3302)
							(mid -0.402042 0.402042)
							(end -0.3302 0.4318)
						)
						(arc
							(start 0.3302 0.4318)
							(mid 0.402042 0.402042)
							(end 0.4318 0.3302)
						)
						(arc
							(start 0.4318 -0.3302)
							(mid 0.402042 -0.402042)
							(end 0.3302 -0.4318)
						)
					)
					(width 0)
					(fill yes)
				)
			)
		)
	)
	(footprint ""
		(layer "F.Cu")
		(at 24.4094 -89.0524)
		(property "Reference" "U46"
			(at 0 0 0)
			(layer "F.SilkS")
			(hide yes)
			(effects
				(font
					(size 1.27 1.27)
				)
			)
		)
		(property "Value" "PCA9306DCTR-GP"
			(at 0 -11.6332 0)
			(unlocked yes)
			(layer "F.Fab")
			(hide yes)
			(effects
				(font
					(size 1.016 1.016)
					(thickness 0.1524)
				)
			)
		)
		(property "Device Type" "SSOIC8H52"
			(at 0 -13.1572 0)
			(unlocked yes)
			(layer "F.Fab")
			(hide yes)
			(effects
				(font
					(size 1.016 1.016)
					(thickness 0.1524)
				)
			)
		)
		(duplicate_pad_numbers_are_jumpers no)
		(fp_line
			(start -1.7018 -0.5842)
			(end -1.7018 2.286)
			(stroke
				(width 0.1524)
				(type default)
			)
			(layer "F.SilkS")
		)
		(fp_line
			(start -1.7018 -0.5842)
			(end 1.0668 -0.5842)
			(stroke
				(width 0.1524)
				(type default)
			)
			(layer "F.SilkS")
		)
		(fp_line
			(start -1.524 0.5842)
			(end -1.524 2.286)
			(stroke
				(width 0.508)
				(type default)
			)
			(layer "F.SilkS")
		)
		(fp_line
			(start -1.397 0)
			(end -1.7018 -0.3048)
			(stroke
				(width 0.1524)
				(type default)
			)
			(layer "F.SilkS")
		)
		(fp_line
			(start -1.397 0)
			(end -1.7018 0.3048)
			(stroke
				(width 0.1524)
				(type default)
			)
			(layer "F.SilkS")
		)
		(fp_line
			(start 1.0668 -0.5842)
			(end 1.0668 0.5842)
			(stroke
				(width 0.1524)
				(type default)
			)
			(layer "F.SilkS")
		)
		(fp_line
			(start 1.0668 0.5842)
			(end -1.524 0.5842)
			(stroke
				(width 0.1524)
				(type default)
			)
			(layer "F.SilkS")
		)
		(fp_poly
			(pts
				(xy -1.1684 -0.5842) (xy 1.0668 -0.5842) (xy 1.0668 0.5842) (xy -1.1684 0.5842)
			)
			(stroke
				(width 0)
				(type default)
			)
			(fill yes)
			(layer "F.SilkS")
		)
		(fp_poly
			(pts
				(xy -1.778 2.54) (xy 1.778 2.54) (xy 1.778 -2.54) (xy -1.778 -2.54)
			)
			(stroke
				(width 0)
				(type default)
			)
			(fill no)
			(layer "F.CrtYd")
		)
		(fp_poly
			(pts
				(xy -1.778 -2.54) (xy 1.778 -2.54) (xy 1.778 2.54) (xy -1.778 2.54)
			)
			(stroke
				(width 0)
				(type default)
			)
			(fill no)
			(layer "F.Fab")
		)
		(pad "1" smd rect
			(at -0.97536 1.6256)
			(size 0.3556 1.524)
			(layers "F.Cu" "F.Mask" "F.Paste")
			(net "GND")
		)
		(pad "2" smd rect
			(at -0.32512 1.6256)
			(size 0.3556 1.524)
			(layers "F.Cu" "F.Mask" "F.Paste")
			(net "P1V8_E")
		)
		(pad "3" smd rect
			(at 0.32512 1.6256)
			(size 0.3556 1.524)
			(layers "F.Cu" "F.Mask" "F.Paste")
			(net "I2C_BMC_RMT_SCL1_LS")
		)
		(pad "4" smd rect
			(at 0.97536 1.6256)
			(size 0.3556 1.524)
			(layers "F.Cu" "F.Mask" "F.Paste")
			(net "I2C_BMC_RMT_SDA1_LS")
		)
		(pad "5" smd rect
			(at 0.97536 -1.6256)
			(size 0.3556 1.524)
			(layers "F.Cu" "F.Mask" "F.Paste")
			(net "I2C_BMC_RMT_SDA1")
		)
		(pad "6" smd rect
			(at 0.32512 -1.6256)
			(size 0.3556 1.524)
			(layers "F.Cu" "F.Mask" "F.Paste")
			(net "I2C_BMC_RMT_SCL1")
		)
		(pad "7" smd rect
			(at -0.32512 -1.6256)
			(size 0.3556 1.524)
			(layers "F.Cu" "F.Mask" "F.Paste")
			(net "VREF1")
		)
		(pad "8" smd rect
			(at -0.97536 -1.6256)
			(size 0.3556 1.524)
			(layers "F.Cu" "F.Mask" "F.Paste")
			(net "LS_EN_U46")
		)
	)
	(footprint ""
		(layer "F.Cu")
		(at 23.7998 -99.7966)
		(property "Reference" "R558"
			(at 0 0 0)
			(layer "F.SilkS")
			(hide yes)
			(effects
				(font
					(size 1.27 1.27)
				)
			)
		)
		(property "Value" "0R2J-2-GP"
			(at 0.064008 -3.993896 0)
			(unlocked yes)
			(layer "F.Fab")
			(hide yes)
			(effects
				(font
					(size 1.016 1.016)
					(thickness 0.1524)
				)
			)
		)
		(property "Device Type" "R402H16"
			(at 0.064008 -5.517896 0)
			(unlocked yes)
			(layer "F.Fab")
			(hide yes)
			(effects
				(font
					(size 1.016 1.016)
					(thickness 0.1524)
				)
			)
		)
		(duplicate_pad_numbers_are_jumpers no)
		(fp_line
			(start -0.508 -0.9398)
			(end -0.508 0.9398)
			(stroke
				(width 0.1524)
				(type default)
			)
			(layer "F.SilkS")
		)
		(fp_line
			(start 0.508 -0.9398)
			(end -0.508 -0.9398)
			(stroke
				(width 0.1524)
				(type default)
			)
			(layer "F.SilkS")
		)
		(fp_rect
			(start -0.508 0.9398)
			(end 0.508 -0.9398)
			(stroke
				(width 0)
				(type default)
			)
			(fill no)
			(layer "F.CrtYd")
		)
		(fp_rect
			(start -0.508 0.9398)
			(end 0.508 -0.9398)
			(stroke
				(width 0)
				(type default)
			)
			(fill no)
			(layer "F.Fab")
		)
		(pad "1" smd custom
			(at 0 -0.4445)
			(size 0.1397 0.1397)
			(layers "F.Cu" "F.Mask" "F.Paste")
			(net "SCC_STBY_PGOOD_R")
			(options
				(clearance outline)
				(anchor circle)
			)
			(primitives
				(gr_poly
					(pts
						(arc
							(start -0.1778 -0.2794)
							(mid -0.249642 -0.249642)
							(end -0.2794 -0.1778)
						)
						(arc
							(start -0.2794 0.1778)
							(mid -0.249642 0.249642)
							(end -0.1778 0.2794)
						)
						(arc
							(start 0.1778 0.2794)
							(mid 0.249642 0.249642)
							(end 0.2794 0.1778)
						)
						(arc
							(start 0.2794 -0.1778)
							(mid 0.249642 -0.249642)
							(end 0.1778 -0.2794)
						)
					)
					(width 0)
					(fill yes)
				)
			)
		)
		(pad "2" smd custom
			(at 0 0.4445)
			(size 0.1397 0.1397)
			(layers "F.Cu" "F.Mask" "F.Paste")
			(net "SCC_STBY_PGOOD")
			(options
				(clearance outline)
				(anchor circle)
			)
			(primitives
				(gr_poly
					(pts
						(arc
							(start -0.1778 -0.2794)
							(mid -0.249642 -0.249642)
							(end -0.2794 -0.1778)
						)
						(arc
							(start -0.2794 0.1778)
							(mid -0.249642 0.249642)
							(end -0.1778 0.2794)
						)
						(arc
							(start 0.1778 0.2794)
							(mid 0.249642 0.249642)
							(end 0.2794 0.1778)
						)
						(arc
							(start 0.2794 -0.1778)
							(mid 0.249642 -0.249642)
							(end 0.1778 -0.2794)
						)
					)
					(width 0)
					(fill yes)
				)
			)
		)
	)
	(footprint ""
		(layer "F.Cu")
		(at 63.71463 -71.051928 -90)
		(property "Reference" "C551"
			(at 0 0 270)
			(layer "F.SilkS")
			(hide yes)
			(effects
				(font
					(size 1.27 1.27)
				)
			)
		)
		(property "Value" "SCD1U16V2KX-3GP"
			(at 1.1811 -2.7051 270)
			(unlocked yes)
			(layer "F.Fab")
			(hide yes)
			(effects
				(font
					(size 1.016 1.016)
					(thickness 0.1524)
				)
			)
		)
		(property "Device Type" "C402H22"
			(at 1.1811 -4.2291 270)
			(unlocked yes)
			(layer "F.Fab")
			(hide yes)
			(effects
				(font
					(size 1.016 1.016)
					(thickness 0.1524)
				)
			)
		)
		(duplicate_pad_numbers_are_jumpers no)
		(fp_rect
			(start -0.4318 0.9525)
			(end 0.4318 -0.9525)
			(stroke
				(width 0)
				(type default)
			)
			(fill no)
			(layer "F.CrtYd")
		)
		(fp_rect
			(start -0.4318 0.9525)
			(end 0.4318 -0.9525)
			(stroke
				(width 0)
				(type default)
			)
			(fill no)
			(layer "F.Fab")
		)
		(pad "1" smd custom
			(at 0 -0.4445 270)
			(size 0.1524 0.1524)
			(layers "F.Cu" "F.Mask" "F.Paste")
			(net "VREF5")
			(options
				(clearance outline)
				(anchor circle)
			)
			(primitives
				(gr_poly
					(pts
						(arc
							(start 0.3048 -0.2032)
							(mid 0.275042 -0.275042)
							(end 0.2032 -0.3048)
						)
						(arc
							(start -0.2032 -0.3048)
							(mid -0.275042 -0.275042)
							(end -0.3048 -0.2032)
						)
						(arc
							(start -0.3048 0.2032)
							(mid -0.275042 0.275042)
							(end -0.2032 0.3048)
						)
						(arc
							(start 0.2032 0.3048)
							(mid 0.275042 0.275042)
							(end 0.3048 0.2032)
						)
					)
					(width 0)
					(fill yes)
				)
			)
		)
		(pad "2" smd custom
			(at 0 0.4445 270)
			(size 0.1524 0.1524)
			(layers "F.Cu" "F.Mask" "F.Paste")
			(net "GND")
			(options
				(clearance outline)
				(anchor circle)
			)
			(primitives
				(gr_poly
					(pts
						(arc
							(start 0.3048 -0.2032)
							(mid 0.275042 -0.275042)
							(end 0.2032 -0.3048)
						)
						(arc
							(start -0.2032 -0.3048)
							(mid -0.275042 -0.275042)
							(end -0.3048 -0.2032)
						)
						(arc
							(start -0.3048 0.2032)
							(mid -0.275042 0.275042)
							(end -0.2032 0.3048)
						)
						(arc
							(start 0.2032 0.3048)
							(mid 0.275042 0.275042)
							(end 0.3048 0.2032)
						)
					)
					(width 0)
					(fill yes)
				)
			)
		)
	)
)
